# S9S_MB_2U (Grand Teton) — schematic netlist excerpt (pin names and nets, part order shuffled) for the footprints in the layout excerpt that follows; sources: Cadence DE-HDL packaged netlist, KiCad conversion of 03242023_DA0F0TMBIJ0_F0T_Motherboard_J_brd_V01_OCP.brd

R2404  Q_RES  1K 1% CHIP  pkg 0402LF  page 278 : A = P3V3_AUX ; B = IRQ_PVCCD_CPU0_VRHOT_LVC3_N
C2044  Q_CAP  100PF 50V 5% EMPTY  pkg 0402  page 250 : A = P5V_ADC_MAM ; B = GND

(kicad_pcb
	(version 20260206)
	(generator "pcbnew")
	(generator_version "10.0")
	(general
		(thickness 1.6)
		(legacy_teardrops no)
	)
	(paper "A4")
	(title_block
		(title "03242023_DA0F0TMBIJ0_F0T_Motherboard_J_brd_V01_OCP.brd")
		(comment 1 "Grand Teton / footprints 3212-3213 of 6105")
	)
	(layers
		(0 "F.Cu" signal "TOP")
		(4 "In1.Cu" signal "GND")
		(6 "In2.Cu" signal "IN1")
		(8 "In3.Cu" signal "GND1")
		(10 "In4.Cu" signal "IN2")
		(12 "In5.Cu" signal "GND2")
		(14 "In6.Cu" signal "IN3")
		(16 "In7.Cu" signal "GND3")
		(18 "In8.Cu" signal "VCC")
		(20 "In9.Cu" signal "VCC1")
		(22 "In10.Cu" signal "GND4")
		(24 "In11.Cu" signal "IN4")
		(26 "In12.Cu" signal "GND5")
		(28 "In13.Cu" signal "IN5")
		(30 "In14.Cu" signal "GND6")
		(32 "In15.Cu" signal "IN6")
		(34 "In16.Cu" signal "GND7")
		(2 "B.Cu" signal "BOTTOM")
		(9 "F.Adhes" user "F.Adhesive")
		(11 "B.Adhes" user "B.Adhesive")
		(13 "F.Paste" user "Package Geometry/Pastemask Top")
		(15 "B.Paste" user "Package Geometry/Pastemask Bottom")
		(5 "F.SilkS" user "Ref Des/Silkscreen Top")
		(7 "B.SilkS" user "Ref Des/Silkscreen Bottom")
		(1 "F.Mask" user "Board Geometry/Soldermask Top")
		(3 "B.Mask" user "Board Geometry/Soldermask Bottom")
		(17 "Dwgs.User" user "User.Drawings")
		(19 "Cmts.User" user "User.Comments")
		(21 "Eco1.User" user "User.Eco1")
		(23 "Eco2.User" user "User.Eco2")
		(25 "Edge.Cuts" user "Board Geometry/Outline")
		(27 "Margin" user)
		(31 "F.CrtYd" user "Package Geometry/Place Bound Top")
		(29 "B.CrtYd" user "Package Geometry/Place Bound Bottom")
		(35 "F.Fab" user "Ref Des/Assembly Top")
		(33 "B.Fab" user "Ref Des/Assembly Bottom")
	)
	(footprint ""
		(layer "F.Cu")
		(at 439.262266 -122.089926 180)
		(property "Reference" "R2404"
			(at 0 0 180)
			(layer "F.SilkS")
			(hide yes)
			(effects
				(font
					(size 1.27 1.27)
				)
			)
		)
		(property "Value" ""
			(at 0 0 180)
			(layer "F.Fab")
			(effects
				(font
					(size 1.27 1.27)
				)
			)
		)
		(duplicate_pad_numbers_are_jumpers no)
		(fp_line
			(start 0.7874 0.4064)
			(end -0.7874 0.4064)
			(stroke
				(width 0.1524)
				(type default)
			)
			(layer "F.SilkS")
		)
		(fp_line
			(start 0.7874 -0.4064)
			(end 0.7874 0.4064)
			(stroke
				(width 0.1524)
				(type default)
			)
			(layer "F.SilkS")
		)
		(fp_line
			(start -0.7874 0.4064)
			(end -0.7874 -0.4064)
			(stroke
				(width 0.1524)
				(type default)
			)
			(layer "F.SilkS")
		)
		(fp_line
			(start -0.7874 -0.4064)
			(end 0.7874 -0.4064)
			(stroke
				(width 0.1524)
				(type default)
			)
			(layer "F.SilkS")
		)
		(fp_line
			(start 0.67945 0.3048)
			(end 0.120396 0.3048)
			(stroke
				(width 0.1)
				(type default)
			)
			(layer "F.Fab")
		)
		(fp_line
			(start 0.67945 -0.3048)
			(end 0.67945 0.3048)
			(stroke
				(width 0.1)
				(type default)
			)
			(layer "F.Fab")
		)
		(fp_line
			(start 0.12065 -0.2794)
			(end 0.12065 -0.3048)
			(stroke
				(width 0.1)
				(type default)
			)
			(layer "F.Fab")
		)
		(fp_line
			(start 0.12065 -0.3048)
			(end 0.67945 -0.3048)
			(stroke
				(width 0.1)
				(type default)
			)
			(layer "F.Fab")
		)
		(fp_line
			(start 0.120396 0.3048)
			(end 0.120396 0.2794)
			(stroke
				(width 0.1)
				(type default)
			)
			(layer "F.Fab")
		)
		(fp_line
			(start 0.120396 0.2794)
			(end -0.12065 0.2794)
			(stroke
				(width 0.1)
				(type default)
			)
			(layer "F.Fab")
		)
		(fp_line
			(start -0.12065 0.3048)
			(end -0.67945 0.3048)
			(stroke
				(width 0.1)
				(type default)
			)
			(layer "F.Fab")
		)
		(fp_line
			(start -0.12065 0.2794)
			(end -0.12065 0.3048)
			(stroke
				(width 0.1)
				(type default)
			)
			(layer "F.Fab")
		)
		(fp_line
			(start -0.12065 -0.2794)
			(end 0.12065 -0.2794)
			(stroke
				(width 0.1)
				(type default)
			)
			(layer "F.Fab")
		)
		(fp_line
			(start -0.12065 -0.305054)
			(end -0.12065 -0.2794)
			(stroke
				(width 0.1)
				(type default)
			)
			(layer "F.Fab")
		)
		(fp_line
			(start -0.67945 0.3048)
			(end -0.67945 -0.305054)
			(stroke
				(width 0.1)
				(type default)
			)
			(layer "F.Fab")
		)
		(fp_line
			(start -0.67945 -0.305054)
			(end -0.12065 -0.305054)
			(stroke
				(width 0.1)
				(type default)
			)
			(layer "F.Fab")
		)
		(pad "1" smd circle
			(at -0.40005 0 180)
			(size 0 0)
			(layers "F.Cu" "F.Mask" "F.Paste")
			(net "P3V3_AUX")
		)
		(pad "2" smd circle
			(at 0.40005 0 180)
			(size 0 0)
			(layers "F.Cu" "F.Mask" "F.Paste")
			(net "IRQ_PVCCD_CPU0_VRHOT_LVC3_N")
		)
	)
	(footprint ""
		(layer "F.Cu")
		(at 32.761428 -97.554034 180)
		(property "Reference" "C2044"
			(at 0 0 180)
			(layer "F.SilkS")
			(hide yes)
			(effects
				(font
					(size 1.27 1.27)
				)
			)
		)
		(property "Value" ""
			(at 0 0 180)
			(layer "F.Fab")
			(effects
				(font
					(size 1.27 1.27)
				)
			)
		)
		(duplicate_pad_numbers_are_jumpers no)
		(fp_line
			(start 0.7874 0.4064)
			(end -0.7874 0.4064)
			(stroke
				(width 0.1524)
				(type default)
			)
			(layer "F.SilkS")
		)
		(fp_line
			(start 0.7874 -0.4064)
			(end 0.7874 0.4064)
			(stroke
				(width 0.1524)
				(type default)
			)
			(layer "F.SilkS")
		)
		(fp_line
			(start -0.7874 0.4064)
			(end -0.7874 -0.4064)
			(stroke
				(width 0.1524)
				(type default)
			)
			(layer "F.SilkS")
		)
		(fp_line
			(start -0.7874 -0.4064)
			(end 0.7874 -0.4064)
			(stroke
				(width 0.1524)
				(type default)
			)
			(layer "F.SilkS")
		)
		(fp_line
			(start 0.67945 0.3048)
			(end 0.120396 0.3048)
			(stroke
				(width 0.1)
				(type default)
			)
			(layer "F.Fab")
		)
		(fp_line
			(start 0.67945 -0.3048)
			(end 0.67945 0.3048)
			(stroke
				(width 0.1)
				(type default)
			)
			(layer "F.Fab")
		)
		(fp_line
			(start 0.12065 -0.2794)
			(end 0.12065 -0.3048)
			(stroke
				(width 0.1)
				(type default)
			)
			(layer "F.Fab")
		)
		(fp_line
			(start 0.12065 -0.3048)
			(end 0.67945 -0.3048)
			(stroke
				(width 0.1)
				(type default)
			)
			(layer "F.Fab")
		)
		(fp_line
			(start 0.120396 0.3048)
			(end 0.120396 0.2794)
			(stroke
				(width 0.1)
				(type default)
			)
			(layer "F.Fab")
		)
		(fp_line
			(start 0.120396 0.2794)
			(end -0.12065 0.2794)
			(stroke
				(width 0.1)
				(type default)
			)
			(layer "F.Fab")
		)
		(fp_line
			(start -0.12065 0.3048)
			(end -0.67945 0.3048)
			(stroke
				(width 0.1)
				(type default)
			)
			(layer "F.Fab")
		)
		(fp_line
			(start -0.12065 0.2794)
			(end -0.12065 0.3048)
			(stroke
				(width 0.1)
				(type default)
			)
			(layer "F.Fab")
		)
		(fp_line
			(start -0.12065 -0.2794)
			(end 0.12065 -0.2794)
			(stroke
				(width 0.1)
				(type default)
			)
			(layer "F.Fab")
		)
		(fp_line
			(start -0.12065 -0.305054)
			(end -0.12065 -0.2794)
			(stroke
				(width 0.1)
				(type default)
			)
			(layer "F.Fab")
		)
		(fp_line
			(start -0.67945 0.3048)
			(end -0.67945 -0.305054)
			(stroke
				(width 0.1)
				(type default)
			)
			(layer "F.Fab")
		)
		(fp_line
			(start -0.67945 -0.305054)
			(end -0.12065 -0.305054)
			(stroke
				(width 0.1)
				(type default)
			)
			(layer "F.Fab")
		)
		(pad "1" smd circle
			(at -0.40005 0 180)
			(size 0 0)
			(layers "F.Cu" "F.Mask" "F.Paste")
			(net "P5V_ADC_MAM")
		)
		(pad "2" smd circle
			(at 0.40005 0 180)
			(size 0 0)
			(layers "F.Cu" "F.Mask" "F.Paste")
			(net "GND")
		)
	)
)
